# BASEBOARD_FAB2 (Tioga Pass) — schematic netlist excerpt (pin names and nets, part order shuffled) for the footprints in the layout excerpt that follows; sources: Cadence DE-HDL packaged netlist, KiCad conversion of Wiwynn_Tioga_Pass_MB.brd

C7G4  CAP  220PF 50V 10% X7R  pkg 0402LF  page 215 : A = VR_PVDDQ_ABC_AVSP ; B = VSENSE_PVDDQ_ABC_N
R7E17  RES  0.0 5% CHIP  pkg 0402  page 241 : A = VR_FET_SW_P5V_STBY_PVIN ; B = VR_P5V_STBY_VIN
SH3D1  SHUNT  EMPTY  pkg SH0201  page 214 : A = VSENSE_PVCCIO_CPU1_SKT_VRTN ; B = VSENSE_PVCCIO_CPU1_AVSN

(kicad_pcb
	(version 20260206)
	(generator "pcbnew")
	(generator_version "10.0")
	(general
		(thickness 1.6)
		(legacy_teardrops no)
	)
	(paper "A4")
	(title_block
		(title "Wiwynn_Tioga_Pass_MB.brd")
		(comment 1 "Tioga Pass / footprints 423-425 of 4770")
	)
	(layers
		(0 "F.Cu" signal "TOP")
		(4 "In1.Cu" signal "L2GND")
		(6 "In2.Cu" signal "L3")
		(8 "In3.Cu" signal "L4GND")
		(10 "In4.Cu" signal "L5")
		(12 "In5.Cu" signal "L6GND")
		(14 "In6.Cu" signal "L7VCC")
		(16 "In7.Cu" signal "L8VCC")
		(18 "In8.Cu" signal "L9GND")
		(20 "In9.Cu" signal "L10")
		(22 "In10.Cu" signal "L11GND")
		(24 "In11.Cu" signal "L12")
		(26 "In12.Cu" signal "L13GND")
		(2 "B.Cu" signal "BOTTOM")
		(9 "F.Adhes" user "F.Adhesive")
		(11 "B.Adhes" user "B.Adhesive")
		(13 "F.Paste" user "Package Geometry/Pastemask Top")
		(15 "B.Paste" user "Package Geometry/Pastemask Bottom")
		(5 "F.SilkS" user "Ref Des/Silkscreen Top")
		(7 "B.SilkS" user "Ref Des/Silkscreen Bottom")
		(1 "F.Mask" user "Board Geometry/Soldermask Top")
		(3 "B.Mask" user "Board Geometry/Soldermask Bottom")
		(17 "Dwgs.User" user "User.Drawings")
		(19 "Cmts.User" user "User.Comments")
		(21 "Eco1.User" user "User.Eco1")
		(23 "Eco2.User" user "User.Eco2")
		(25 "Edge.Cuts" user "Board Geometry/Outline")
		(27 "Margin" user)
		(31 "F.CrtYd" user "Package Geometry/Place Bound Top")
		(29 "B.CrtYd" user "Package Geometry/Place Bound Bottom")
		(35 "F.Fab" user "Ref Des/Assembly Top")
		(33 "B.Fab" user "Ref Des/Assembly Bottom")
	)
	(footprint ""
		(layer "F.Cu")
		(at 162.306 -65.7606 90)
		(property "Reference" "SH3D1"
			(at 0 0 90)
			(layer "F.SilkS")
			(hide yes)
			(effects
				(font
					(size 1.27 1.27)
				)
			)
		)
		(property "Value" ""
			(at 0 0 90)
			(layer "F.Fab")
			(effects
				(font
					(size 1.27 1.27)
				)
			)
		)
		(duplicate_pad_numbers_are_jumpers no)
		(fp_poly
			(pts
				(xy -0.1651 -0.0508) (xy -0.1651 0.5842) (xy 0.1651 0.5842) (xy 0.1651 -0.0508)
			)
			(stroke
				(width 0)
				(type default)
			)
			(fill no)
			(layer "F.CrtYd")
		)
		(fp_line
			(start 0.1651 -0.0508)
			(end 0.1651 0.5842)
			(stroke
				(width 0.1)
				(type default)
			)
			(layer "F.Fab")
		)
		(fp_line
			(start -0.1651 -0.0508)
			(end 0.1651 -0.0508)
			(stroke
				(width 0.1)
				(type default)
			)
			(layer "F.Fab")
		)
		(fp_line
			(start 0.1651 0.5842)
			(end -0.1651 0.5842)
			(stroke
				(width 0.1)
				(type default)
			)
			(layer "F.Fab")
		)
		(fp_line
			(start -0.1651 0.5842)
			(end -0.1651 -0.0508)
			(stroke
				(width 0.1)
				(type default)
			)
			(layer "F.Fab")
		)
		(pad "1" smd custom
			(at 0 0 270)
			(size 0.0762 0.0762)
			(layers "F.Cu" "F.Mask" "F.Paste")
			(net "VSENSE_PVCCIO_CPU1_SKT_VRTN")
			(options
				(clearance outline)
				(anchor circle)
			)
			(primitives
				(gr_poly
					(pts
						(arc
							(start -0.1524 -0.10795)
							(mid -0.098518 -0.130268)
							(end -0.0762 -0.18415)
						)
						(xy -0.0762 -0.22225) (xy 0.0762 -0.22225)
						(arc
							(start 0.0762 -0.18415)
							(mid 0.098518 -0.130268)
							(end 0.1524 -0.10795)
						)
						(xy 0.1524 0.22225) (xy -0.1524 0.22225)
					)
					(width 0)
					(fill yes)
				)
			)
		)
		(pad "2" smd custom
			(at 0 0.5334 90)
			(size 0.0762 0.0762)
			(layers "F.Cu" "F.Mask" "F.Paste")
			(net "VSENSE_PVCCIO_CPU1_AVSN")
			(options
				(clearance outline)
				(anchor circle)
			)
			(primitives
				(gr_poly
					(pts
						(arc
							(start -0.1524 -0.10795)
							(mid -0.098518 -0.130268)
							(end -0.0762 -0.18415)
						)
						(xy -0.0762 -0.22225) (xy 0.0762 -0.22225)
						(arc
							(start 0.0762 -0.18415)
							(mid 0.098518 -0.130268)
							(end 0.1524 -0.10795)
						)
						(xy 0.1524 0.22225) (xy -0.1524 0.22225)
					)
					(width 0)
					(fill yes)
				)
			)
		)
	)
	(footprint ""
		(layer "F.Cu")
		(at 389.382 -66.3194)
		(property "Reference" "R7E17"
			(at 0 0 0)
			(layer "F.SilkS")
			(hide yes)
			(effects
				(font
					(size 1.27 1.27)
				)
			)
		)
		(property "Value" ""
			(at 0 0 0)
			(layer "F.Fab")
			(effects
				(font
					(size 1.27 1.27)
				)
			)
		)
		(duplicate_pad_numbers_are_jumpers no)
		(fp_poly
			(pts
				(xy -0.2794 -0.1016) (xy 0.2794 -0.1016) (xy 0.2794 0.9906) (xy -0.2794 0.9906)
			)
			(stroke
				(width 0)
				(type default)
			)
			(fill no)
			(layer "F.CrtYd")
		)
		(fp_line
			(start -0.2794 -0.1016)
			(end -0.2794 0.9906)
			(stroke
				(width 0.1)
				(type default)
			)
			(layer "F.Fab")
		)
		(fp_line
			(start -0.2794 0.9906)
			(end 0.2794 0.9906)
			(stroke
				(width 0.1)
				(type default)
			)
			(layer "F.Fab")
		)
		(fp_line
			(start 0.2794 -0.1016)
			(end -0.2794 -0.1016)
			(stroke
				(width 0.1)
				(type default)
			)
			(layer "F.Fab")
		)
		(fp_line
			(start 0.2794 0.9906)
			(end 0.2794 -0.1016)
			(stroke
				(width 0.1)
				(type default)
			)
			(layer "F.Fab")
		)
		(pad "1" smd rect
			(at 0 0)
			(size 0.508 0.508)
			(layers "F.Cu" "F.Mask" "F.Paste")
			(net "VR_FET_SW_P5V_STBY_PVIN")
		)
		(pad "2" smd rect
			(at 0 0.889)
			(size 0.508 0.508)
			(layers "F.Cu" "F.Mask" "F.Paste")
			(net "VR_P5V_STBY_VIN")
		)
		(zone
			(layer "F.Cu")
			(hatch none 0.5)
			(connect_pads
				(clearance 0)
			)
			(min_thickness 0.25)
			(keepout
				(tracks allowed)
				(vias not_allowed)
				(pads allowed)
				(copperpour not_allowed)
				(footprints allowed)
			)
			(placement
				(enabled no)
				(sheetname "")
			)
			(fill
				(thermal_gap 0.5)
				(thermal_bridge_width 0.5)
				(island_removal_mode 0)
			)
			(polygon
				(pts
					(xy 389.128 -66.0654) (xy 389.636 -66.0654) (xy 389.636 -65.6844) (xy 389.128 -65.6844)
				)
			)
		)
		(zone
			(layer "F.Cu")
			(hatch none 0.5)
			(connect_pads
				(clearance 0)
			)
			(min_thickness 0.25)
			(keepout
				(tracks not_allowed)
				(vias allowed)
				(pads allowed)
				(copperpour not_allowed)
				(footprints allowed)
			)
			(placement
				(enabled no)
				(sheetname "")
			)
			(fill
				(thermal_gap 0.5)
				(thermal_bridge_width 0.5)
				(island_removal_mode 0)
			)
			(polygon
				(pts
					(xy 389.128 -65.6844) (xy 389.636 -65.6844) (xy 389.636 -66.0654) (xy 389.128 -66.0654)
				)
			)
		)
	)
	(footprint ""
		(layer "F.Cu")
		(at 338.836 -13.1826 -90)
		(property "Reference" "C7G4"
			(at 0 0 270)
			(layer "F.SilkS")
			(hide yes)
			(effects
				(font
					(size 1.27 1.27)
				)
			)
		)
		(property "Value" ""
			(at 0 0 270)
			(layer "F.Fab")
			(effects
				(font
					(size 1.27 1.27)
				)
			)
		)
		(duplicate_pad_numbers_are_jumpers no)
		(fp_rect
			(start -0.3048 0.9906)
			(end 0.3048 -0.1016)
			(stroke
				(width 0)
				(type default)
			)
			(fill no)
			(layer "F.CrtYd")
		)
		(fp_line
			(start -0.3048 0.9906)
			(end 0.3048 0.9906)
			(stroke
				(width 0.1)
				(type default)
			)
			(layer "F.Fab")
		)
		(fp_line
			(start 0.3048 0.9906)
			(end 0.3048 -0.1016)
			(stroke
				(width 0.1)
				(type default)
			)
			(layer "F.Fab")
		)
		(fp_line
			(start -0.3048 -0.1016)
			(end -0.3048 0.9906)
			(stroke
				(width 0.1)
				(type default)
			)
			(layer "F.Fab")
		)
		(fp_line
			(start 0.3048 -0.1016)
			(end -0.3048 -0.1016)
			(stroke
				(width 0.1)
				(type default)
			)
			(layer "F.Fab")
		)
		(pad "1" smd rect
			(at 0 0 270)
			(size 0.508 0.508)
			(layers "F.Cu" "F.Mask" "F.Paste")
			(net "VR_PVDDQ_ABC_AVSP")
		)
		(pad "2" smd rect
			(at 0 0.889 270)
			(size 0.508 0.508)
			(layers "F.Cu" "F.Mask" "F.Paste")
			(net "VSENSE_PVDDQ_ABC_N")
		)
		(zone
			(layer "F.Cu")
			(hatch none 0.5)
			(connect_pads
				(clearance 0)
			)
			(min_thickness 0.25)
			(keepout
				(tracks allowed)
				(vias not_allowed)
				(pads allowed)
				(copperpour not_allowed)
				(footprints allowed)
			)
			(placement
				(enabled no)
				(sheetname "")
			)
			(fill
				(thermal_gap 0.5)
				(thermal_bridge_width 0.5)
				(island_removal_mode 0)
			)
			(polygon
				(pts
					(xy 338.201 -13.4366) (xy 338.201 -12.9286) (xy 338.582 -12.9286) (xy 338.582 -13.4366)
				)
			)
		)
	)
)
